# BASEBOARD_FAB2 (Tioga Pass) — schematic netlist excerpt (pin names and nets, part order shuffled) for the footprints in the layout excerpt that follows; sources: Cadence DE-HDL packaged netlist, KiCad conversion of Wiwynn_Tioga_Pass_MB.brd

Q7E5  FET_N_DUAL  NTJD4001N FET  pkg SMLF  page 95
  SOURCE(0)  = GND
  GATE(0)  = IRQ_CPU0_PROCHOT_G_N
  DRAIN(0)  = H_CPU0_PROCHOT_G_N
  SOURCE(0)  = GND
  GATE(0)  = IRQ_CPU0_VRHOT
  DRAIN(0)  = IRQ_CPU0_VRHOT

R2U32  RES  20.0 1% CHIP  pkg 0402  page 108 : A = SMB_SLOTX24_BMC_STBY_LVC3_SCL ; B = SMB_SLOTX24_STBY_LVC3_SCL_R2

(kicad_pcb
	(version 20260206)
	(generator "pcbnew")
	(generator_version "10.0")
	(general
		(thickness 1.6)
		(legacy_teardrops no)
	)
	(paper "A4")
	(title_block
		(title "Wiwynn_Tioga_Pass_MB.brd")
		(comment 1 "Tioga Pass / footprints 4513-4514 of 4770")
	)
	(layers
		(0 "F.Cu" signal "TOP")
		(4 "In1.Cu" signal "L2GND")
		(6 "In2.Cu" signal "L3")
		(8 "In3.Cu" signal "L4GND")
		(10 "In4.Cu" signal "L5")
		(12 "In5.Cu" signal "L6GND")
		(14 "In6.Cu" signal "L7VCC")
		(16 "In7.Cu" signal "L8VCC")
		(18 "In8.Cu" signal "L9GND")
		(20 "In9.Cu" signal "L10")
		(22 "In10.Cu" signal "L11GND")
		(24 "In11.Cu" signal "L12")
		(26 "In12.Cu" signal "L13GND")
		(2 "B.Cu" signal "BOTTOM")
		(9 "F.Adhes" user "F.Adhesive")
		(11 "B.Adhes" user "B.Adhesive")
		(13 "F.Paste" user "Package Geometry/Pastemask Top")
		(15 "B.Paste" user "Package Geometry/Pastemask Bottom")
		(5 "F.SilkS" user "Ref Des/Silkscreen Top")
		(7 "B.SilkS" user "Ref Des/Silkscreen Bottom")
		(1 "F.Mask" user "Board Geometry/Soldermask Top")
		(3 "B.Mask" user "Board Geometry/Soldermask Bottom")
		(17 "Dwgs.User" user "User.Drawings")
		(19 "Cmts.User" user "User.Comments")
		(21 "Eco1.User" user "User.Eco1")
		(23 "Eco2.User" user "User.Eco2")
		(25 "Edge.Cuts" user "Board Geometry/Outline")
		(27 "Margin" user)
		(31 "F.CrtYd" user "Package Geometry/Place Bound Top")
		(29 "B.CrtYd" user "Package Geometry/Place Bound Bottom")
		(35 "F.Fab" user "Ref Des/Assembly Top")
		(33 "B.Fab" user "Ref Des/Assembly Bottom")
	)
	(footprint ""
		(layer "B.Cu")
		(at 374.231916 -37.063426 180)
		(property "Reference" "Q7E5"
			(at -2.94005 3.6957 90)
			(unlocked yes)
			(layer "B.SilkS")
			(effects
				(font
					(size 0.7874 0.5842)
					(thickness 0.1524)
				)
				(justify left mirror)
			)
		)
		(property "Value" ""
			(at 0 0 0)
			(layer "B.Fab")
			(effects
				(font
					(size 1.27 1.27)
				)
				(justify mirror)
			)
		)
		(duplicate_pad_numbers_are_jumpers no)
		(fp_circle
			(center 0.784352 -0.400558)
			(end 0.657352 -0.400558)
			(stroke
				(width 0.254)
				(type default)
			)
			(fill no)
			(layer "B.SilkS")
		)
		(fp_poly
			(pts
				(xy -0.2159 1.7526) (xy -1.5621 1.7526) (xy -1.5621 -0.4572) (xy -0.2159 -0.4572)
			)
			(stroke
				(width 0)
				(type default)
			)
			(fill no)
			(layer "B.CrtYd")
		)
		(fp_line
			(start -0.2159 1.75514)
			(end -1.5621 1.75514)
			(stroke
				(width 0.1)
				(type default)
			)
			(layer "B.Fab")
		)
		(fp_line
			(start -0.2159 -0.45466)
			(end -0.2159 1.75514)
			(stroke
				(width 0.1)
				(type default)
			)
			(layer "B.Fab")
		)
		(fp_line
			(start -1.5621 1.75514)
			(end -1.5621 -0.45466)
			(stroke
				(width 0.1)
				(type default)
			)
			(layer "B.Fab")
		)
		(fp_line
			(start -1.5621 -0.45466)
			(end -0.2159 -0.45466)
			(stroke
				(width 0.1)
				(type default)
			)
			(layer "B.Fab")
		)
		(fp_circle
			(center 0.508 -0.7874)
			(end 0.381 -0.7874)
			(stroke
				(width 0.254)
				(type default)
			)
			(fill no)
			(layer "B.Fab")
		)
		(pad "1" smd rect
			(at 0 0)
			(size 1.016 0.381)
			(layers "B.Cu" "B.Mask" "B.Paste")
			(net "GND")
		)
		(pad "2" smd rect
			(at 0 0.65024)
			(size 1.016 0.381)
			(layers "B.Cu" "B.Mask" "B.Paste")
			(net "IRQ_CPU0_PROCHOT_G_N")
		)
		(pad "3" smd rect
			(at 0 1.30048)
			(size 1.016 0.381)
			(layers "B.Cu" "B.Mask" "B.Paste")
			(net "H_CPU0_PROCHOT_G_N")
		)
		(pad "4" smd rect
			(at -1.778 1.30048)
			(size 1.016 0.381)
			(layers "B.Cu" "B.Mask" "B.Paste")
			(net "GND")
		)
		(pad "5" smd rect
			(at -1.778 0.65024)
			(size 1.016 0.381)
			(layers "B.Cu" "B.Mask" "B.Paste")
			(net "IRQ_CPU0_VRHOT")
		)
		(pad "6" smd rect
			(at -1.778 0)
			(size 1.016 0.381)
			(layers "B.Cu" "B.Mask" "B.Paste")
			(net "IRQ_CPU0_VRHOT")
		)
		(zone
			(layer "B.Cu")
			(hatch none 0.5)
			(connect_pads
				(clearance 0)
			)
			(min_thickness 0.25)
			(keepout
				(tracks allowed)
				(vias not_allowed)
				(pads allowed)
				(copperpour not_allowed)
				(footprints allowed)
			)
			(placement
				(enabled no)
				(sheetname "")
			)
			(fill
				(thermal_gap 0.5)
				(thermal_bridge_width 0.5)
				(island_removal_mode 0)
			)
			(polygon
				(pts
					(xy 373.723916 -36.872926) (xy 374.739916 -36.872926) (xy 374.739916 -38.562026) (xy 373.723916 -38.562026)
				)
			)
		)
		(zone
			(layer "B.Cu")
			(hatch none 0.5)
			(connect_pads
				(clearance 0)
			)
			(min_thickness 0.25)
			(keepout
				(tracks allowed)
				(vias not_allowed)
				(pads allowed)
				(copperpour not_allowed)
				(footprints allowed)
			)
			(placement
				(enabled no)
				(sheetname "")
			)
			(fill
				(thermal_gap 0.5)
				(thermal_bridge_width 0.5)
				(island_removal_mode 0)
			)
			(polygon
				(pts
					(xy 375.501916 -36.872926) (xy 376.517916 -36.872926) (xy 376.517916 -38.562026) (xy 375.501916 -38.562026)
				)
			)
		)
	)
	(footprint ""
		(layer "B.Cu")
		(at 468.181944 -11.42492)
		(property "Reference" "R2U32"
			(at 0 0 0)
			(layer "B.SilkS")
			(hide yes)
			(effects
				(font
					(size 1.27 1.27)
				)
				(justify mirror)
			)
		)
		(property "Value" ""
			(at 0 0 0)
			(layer "B.Fab")
			(effects
				(font
					(size 1.27 1.27)
				)
				(justify mirror)
			)
		)
		(duplicate_pad_numbers_are_jumpers no)
		(fp_poly
			(pts
				(xy 0.2794 -0.1016) (xy -0.2794 -0.1016) (xy -0.2794 0.9906) (xy 0.2794 0.9906)
			)
			(stroke
				(width 0)
				(type default)
			)
			(fill no)
			(layer "B.CrtYd")
		)
		(fp_line
			(start -0.2794 -0.1016)
			(end 0.2794 -0.1016)
			(stroke
				(width 0.1)
				(type default)
			)
			(layer "B.Fab")
		)
		(fp_line
			(start -0.2794 0.9906)
			(end -0.2794 -0.1016)
			(stroke
				(width 0.1)
				(type default)
			)
			(layer "B.Fab")
		)
		(fp_line
			(start 0.2794 -0.1016)
			(end 0.2794 0.9906)
			(stroke
				(width 0.1)
				(type default)
			)
			(layer "B.Fab")
		)
		(fp_line
			(start 0.2794 0.9906)
			(end -0.2794 0.9906)
			(stroke
				(width 0.1)
				(type default)
			)
			(layer "B.Fab")
		)
		(pad "1" smd rect
			(at 0 0 180)
			(size 0.508 0.508)
			(layers "B.Cu" "B.Mask" "B.Paste")
			(net "SMB_SLOTX24_BMC_STBY_LVC3_SCL")
		)
		(pad "2" smd rect
			(at 0 0.889 180)
			(size 0.508 0.508)
			(layers "B.Cu" "B.Mask" "B.Paste")
			(net "SMB_SLOTX24_STBY_LVC3_SCL_R2")
		)
		(zone
			(layer "B.Cu")
			(hatch none 0.5)
			(connect_pads
				(clearance 0)
			)
			(min_thickness 0.25)
			(keepout
				(tracks allowed)
				(vias not_allowed)
				(pads allowed)
				(copperpour not_allowed)
				(footprints allowed)
			)
			(placement
				(enabled no)
				(sheetname "")
			)
			(fill
				(thermal_gap 0.5)
				(thermal_bridge_width 0.5)
				(island_removal_mode 0)
			)
			(polygon
				(pts
					(xy 468.435944 -11.17092) (xy 467.927944 -11.17092) (xy 467.927944 -10.78992) (xy 468.435944 -10.78992)
				)
			)
		)
		(zone
			(layer "B.Cu")
			(hatch none 0.5)
			(connect_pads
				(clearance 0)
			)
			(min_thickness 0.25)
			(keepout
				(tracks not_allowed)
				(vias allowed)
				(pads allowed)
				(copperpour not_allowed)
				(footprints allowed)
			)
			(placement
				(enabled no)
				(sheetname "")
			)
			(fill
				(thermal_gap 0.5)
				(thermal_bridge_width 0.5)
				(island_removal_mode 0)
			)
			(polygon
				(pts
					(xy 468.435944 -10.78992) (xy 467.927944 -10.78992) (xy 467.927944 -11.17092) (xy 468.435944 -11.17092)
				)
			)
		)
	)
)
